(kicad_pcb
	(version 20241229)
	(generator "pcbnew")
	(generator_version "9.0")
	(general
		(thickness 1.6642)
		(legacy_teardrops no)
	)
	(paper "A3")
	(title_block
		(title "PolarFire SoM")
		(date "2025-07-22")
		(rev "1.1.4")
		(company "Antmicro Ltd")
		(comment 1 "www.antmicro.com")
		(comment 9 "footprints 128-132 of 470")
	)
	(layers
		(0 "F.Cu" mixed)
		(4 "In1.Cu" power)
		(6 "In2.Cu" signal)
		(8 "In3.Cu" power)
		(10 "In4.Cu" signal)
		(12 "In5.Cu" power)
		(14 "In6.Cu" power)
		(16 "In7.Cu" signal)
		(18 "In8.Cu" power)
		(20 "In9.Cu" signal)
		(22 "In10.Cu" power)
		(24 "In11.Cu" signal)
		(26 "In12.Cu" signal)
		(2 "B.Cu" mixed)
		(9 "F.Adhes" user "F.Adhesive")
		(11 "B.Adhes" user "B.Adhesive")
		(13 "F.Paste" user)
		(15 "B.Paste" user)
		(5 "F.SilkS" user "F.Silkscreen")
		(7 "B.SilkS" user "B.Silkscreen")
		(1 "F.Mask" user)
		(3 "B.Mask" user)
		(17 "Dwgs.User" user "User.Drawings")
		(19 "Cmts.User" user "User.Comments")
		(21 "Eco1.User" user "User.Eco1")
		(23 "Eco2.User" user "User.Eco2")
		(25 "Edge.Cuts" user)
		(27 "Margin" user)
		(31 "F.CrtYd" user "F.Courtyard")
		(29 "B.CrtYd" user "B.Courtyard")
		(35 "F.Fab" user)
		(33 "B.Fab" user)
	)
	(footprint "antmicro-footprints:TP_SMD_0.75mm"
		(layer "B.Cu")
		(at 188.2 147.4 180)
		(property "Reference" "TP37"
			(at -3 -0.25 0)
			(layer "B.SilkS")
			(hide yes)
			(effects
				(font
					(size 0.7 0.7)
					(thickness 0.15)
				)
				(justify left bottom mirror)
			)
		)
		(property "Value" "TP_0.75mm_SMD"
			(at 0 -1.2 0)
			(layer "B.Fab")
			(hide yes)
			(effects
				(font
					(size 0.7 0.7)
					(thickness 0.15)
				)
				(justify left bottom mirror)
			)
		)
		(property "Description" "SMT test point"
			(at 0 0 0)
			(layer "B.Fab")
			(hide yes)
			(effects
				(font
					(size 1.27 1.27)
					(thickness 0.15)
				)
				(justify mirror)
			)
		)
		(property "MPN" ""
			(at 0 0 0)
			(unlocked yes)
			(layer "B.Fab")
			(hide yes)
			(effects
				(font
					(size 1 1)
					(thickness 0.15)
				)
				(justify mirror)
			)
		)
		(property "Manufacturer" ""
			(at 0 0 0)
			(unlocked yes)
			(layer "B.Fab")
			(hide yes)
			(effects
				(font
					(size 1 1)
					(thickness 0.15)
				)
				(justify mirror)
			)
		)
		(property "Author" "Antmicro"
			(at 0 0 0)
			(unlocked yes)
			(layer "B.Fab")
			(hide yes)
			(effects
				(font
					(size 1 1)
					(thickness 0.15)
				)
				(justify mirror)
			)
		)
		(property "License" "Apache-2.0"
			(at 0 0 0)
			(unlocked yes)
			(layer "B.Fab")
			(hide yes)
			(effects
				(font
					(size 1 1)
					(thickness 0.15)
				)
				(justify mirror)
			)
		)
		(property "Public" "False"
			(at 0 0 0)
			(unlocked yes)
			(layer "B.Fab")
			(hide yes)
			(effects
				(font
					(size 1 1)
					(thickness 0.15)
				)
				(justify mirror)
			)
		)
		(sheetname "/Supply/")
		(sheetfile "supply.kicad_sch")
		(attr exclude_from_pos_files exclude_from_bom)
		(fp_circle
			(center 0 0)
			(end 0.475 0)
			(stroke
				(width 0.05)
				(type default)
			)
			(fill no)
			(layer "B.CrtYd")
		)
		(fp_text user "Author: Antmicro"
			(at -0.4 -3.901 0)
			(layer "B.Fab")
			(effects
				(font
					(size 0.7 0.7)
					(thickness 0.15)
				)
				(justify left bottom mirror)
			)
		)
		(fp_text user "License: Apache-2.0"
			(at -0.4 -5.101 0)
			(layer "B.Fab")
			(effects
				(font
					(size 0.7 0.7)
					(thickness 0.15)
				)
				(justify left bottom mirror)
			)
		)
		(fp_text user "${REFERENCE}"
			(at -0.4 -2.7 0)
			(layer "B.Fab")
			(effects
				(font
					(size 0.7 0.7)
					(thickness 0.15)
				)
				(justify left bottom mirror)
			)
		)
		(pad "1" smd circle
			(at 0 0 180)
			(size 0.75 0.75)
			(layers "B.Cu" "B.Mask")
			(net 522 "/Supply/1V05_REG")
			(pinfunction "1")
			(pintype "passive")
		)
	)
	(footprint "antmicro-footprints:R_0402_1005Metric"
		(layer "B.Cu")
		(at 213.43 144.15)
		(descr "Resistor SMD 0402")
		(tags "resistor SMD 0402")
		(property "Reference" "R18"
			(at 1.07 1.4 180)
			(layer "B.SilkS")
			(effects
				(font
					(size 0.7 0.7)
					(thickness 0.15)
				)
				(justify left bottom mirror)
			)
		)
		(property "Value" "R_8k06_0402"
			(at -1.011843 -1.772047 180)
			(layer "B.Fab")
			(hide yes)
			(effects
				(font
					(size 0.7 0.7)
					(thickness 0.15)
				)
				(justify left bottom mirror)
			)
		)
		(property "Datasheet" "https://www.bourns.com/docs/product-datasheets/cr.pdf"
			(at 0 0 0)
			(layer "F.Fab")
			(hide yes)
			(effects
				(font
					(size 1.27 1.27)
					(thickness 0.15)
				)
			)
		)
		(property "Description" "SMD Chip Resistor, 8.06 kohm, ± 1%, 63 mW, 0402 [1005 Metric], Thick Film, General Purpose"
			(at 0 0 0)
			(layer "F.Fab")
			(hide yes)
			(effects
				(font
					(size 1.27 1.27)
					(thickness 0.15)
				)
			)
		)
		(property "Author" "Antmicro"
			(at 0 0 0)
			(layer "B.Fab")
			(hide yes)
			(effects
				(font
					(size 1 1)
					(thickness 0.15)
				)
				(justify mirror)
			)
		)
		(property "License" "Apache-2.0"
			(at 0 0 0)
			(layer "B.Fab")
			(hide yes)
			(effects
				(font
					(size 1 1)
					(thickness 0.15)
				)
				(justify mirror)
			)
		)
		(property "MPN" "CR0402-FX-8061GLF"
			(at 0 0 0)
			(layer "B.Fab")
			(hide yes)
			(effects
				(font
					(size 1 1)
					(thickness 0.15)
				)
				(justify mirror)
			)
		)
		(property "Manufacturer" "Bourns"
			(at 0 0 0)
			(layer "B.Fab")
			(hide yes)
			(effects
				(font
					(size 1 1)
					(thickness 0.15)
				)
				(justify mirror)
			)
		)
		(property "Public" ""
			(at 0 0 0)
			(layer "B.Fab")
			(hide yes)
			(effects
				(font
					(size 1 1)
					(thickness 0.15)
				)
				(justify mirror)
			)
		)
		(property "Tolerance" "1%"
			(at 0 0 0)
			(layer "B.Fab")
			(hide yes)
			(effects
				(font
					(size 1 1)
					(thickness 0.15)
				)
				(justify mirror)
			)
		)
		(property "Val" "8k06"
			(at 0 0 0)
			(layer "B.Fab")
			(hide yes)
			(effects
				(font
					(size 1 1)
					(thickness 0.15)
				)
				(justify mirror)
			)
		)
		(sheetname "/USB/")
		(sheetfile "usb.kicad_sch")
		(attr smd)
		(fp_rect
			(start -0.925 0.47)
			(end 0.925 -0.47)
			(stroke
				(width 0.05)
				(type default)
			)
			(fill no)
			(layer "B.CrtYd")
		)
		(fp_rect
			(start -0.5 0.25)
			(end 0.5 -0.25)
			(stroke
				(width 0.15)
				(type solid)
			)
			(fill no)
			(layer "B.Fab")
		)
		(fp_text user "License: Apache-2.0"
			(at -0.95 -5.169 180)
			(layer "B.Fab")
			(effects
				(font
					(size 0.7 0.7)
					(thickness 0.15)
				)
				(justify left bottom mirror)
			)
		)
		(fp_text user "${REFERENCE}"
			(at -0.95 -3.168 180)
			(layer "B.Fab")
			(effects
				(font
					(size 0.7 0.7)
					(thickness 0.15)
				)
				(justify left bottom mirror)
			)
		)
		(fp_text user "Author: Antmicro"
			(at -0.95 -4.169 180)
			(layer "B.Fab")
			(effects
				(font
					(size 0.7 0.7)
					(thickness 0.15)
				)
				(justify left bottom mirror)
			)
		)
		(pad "1" smd roundrect
			(at -0.48 0)
			(size 0.59 0.64)
			(layers "B.Cu" "B.Mask" "B.Paste")
			(roundrect_rratio 0.25)
			(net 280 "Net-(U13-RBIAS)")
			(pintype "passive")
		)
		(pad "2" smd roundrect
			(at 0.48 0)
			(size 0.59 0.64)
			(layers "B.Cu" "B.Mask" "B.Paste")
			(roundrect_rratio 0.25)
			(net 417 "GND")
			(pintype "passive")
		)
	)
	(footprint "antmicro-footprints:C_0402_1005Metric"
		(layer "B.Cu")
		(at 222.75 123 -90)
		(descr "Capacitor SMD 0402")
		(tags "capacitor SMD 0402")
		(property "Reference" "C4"
			(at -1.09 0.51 270)
			(layer "B.SilkS")
			(effects
				(font
					(size 0.7 0.7)
					(thickness 0.15)
				)
				(justify left bottom mirror)
			)
		)
		(property "Value" "C_100n_0402"
			(at -1.022927 -2.155213 90)
			(layer "B.Fab")
			(hide yes)
			(effects
				(font
					(size 0.7 0.7)
					(thickness 0.15)
				)
				(justify left bottom mirror)
			)
		)
		(property "Datasheet" "https://www.murata.com/products/productdetail?partno=GRM155R61H104KE14%23"
			(at 0 0 270)
			(layer "F.Fab")
			(hide yes)
			(effects
				(font
					(size 1.27 1.27)
					(thickness 0.15)
				)
			)
		)
		(property "Description" "SMD Multilayer Ceramic Capacitor, 0.1 µF, 50 V, 0402 [1005 Metric], ± 10%, X5R, GRM Series"
			(at 0 0 270)
			(layer "F.Fab")
			(hide yes)
			(effects
				(font
					(size 1.27 1.27)
					(thickness 0.15)
				)
			)
		)
		(property "Author" "Antmicro"
			(at 99.75 345.75 0)
			(layer "B.Fab")
			(hide yes)
			(effects
				(font
					(size 1 1)
					(thickness 0.15)
				)
				(justify mirror)
			)
		)
		(property "Dielectric" "X5R"
			(at 99.75 345.75 0)
			(layer "B.Fab")
			(hide yes)
			(effects
				(font
					(size 1 1)
					(thickness 0.15)
				)
				(justify mirror)
			)
		)
		(property "License" "Apache-2.0"
			(at 99.75 345.75 0)
			(layer "B.Fab")
			(hide yes)
			(effects
				(font
					(size 1 1)
					(thickness 0.15)
				)
				(justify mirror)
			)
		)
		(property "MPN" "GRM155R61H104KE14D"
			(at 99.75 345.75 0)
			(layer "B.Fab")
			(hide yes)
			(effects
				(font
					(size 1 1)
					(thickness 0.15)
				)
				(justify mirror)
			)
		)
		(property "Manufacturer" "Murata"
			(at 99.75 345.75 0)
			(layer "B.Fab")
			(hide yes)
			(effects
				(font
					(size 1 1)
					(thickness 0.15)
				)
				(justify mirror)
			)
		)
		(property "Public" ""
			(at 99.75 345.75 0)
			(layer "B.Fab")
			(hide yes)
			(effects
				(font
					(size 1 1)
					(thickness 0.15)
				)
				(justify mirror)
			)
		)
		(property "Val" "100n"
			(at 99.75 345.75 0)
			(layer "B.Fab")
			(hide yes)
			(effects
				(font
					(size 1 1)
					(thickness 0.15)
				)
				(justify mirror)
			)
		)
		(property "Voltage" "50V"
			(at 99.75 345.75 0)
			(layer "B.Fab")
			(hide yes)
			(effects
				(font
					(size 1 1)
					(thickness 0.15)
				)
				(justify mirror)
			)
		)
		(sheetname "/FPGA MSS/")
		(sheetfile "fpga-mss.kicad_sch")
		(attr smd)
		(fp_rect
			(start -0.925 0.47)
			(end 0.925 -0.47)
			(stroke
				(width 0.05)
				(type default)
			)
			(fill no)
			(layer "B.CrtYd")
		)
		(fp_line
			(start -0.494 0.25)
			(end 0.504 0.25)
			(stroke
				(width 0.15)
				(type solid)
			)
			(layer "B.Fab")
		)
		(fp_line
			(start 0.504 0.25)
			(end 0.504 -0.248)
			(stroke
				(width 0.15)
				(type solid)
			)
			(layer "B.Fab")
		)
		(fp_line
			(start -0.494 -0.248)
			(end -0.494 0.25)
			(stroke
				(width 0.15)
				(type solid)
			)
			(layer "B.Fab")
		)
		(fp_line
			(start 0.504 -0.248)
			(end -0.494 -0.248)
			(stroke
				(width 0.15)
				(type solid)
			)
			(layer "B.Fab")
		)
		(fp_text user "License: Apache-2.0"
			(at -0.939 -5.799 90)
			(layer "B.Fab")
			(effects
				(font
					(size 0.7 0.7)
					(thickness 0.15)
				)
				(justify left bottom mirror)
			)
		)
		(fp_text user "${REFERENCE}"
			(at -0.939 -4.599 90)
			(layer "B.Fab")
			(effects
				(font
					(size 0.7 0.7)
					(thickness 0.15)
				)
				(justify left bottom mirror)
			)
		)
		(fp_text user "Author: Antmicro"
			(at -0.939 -3.399 90)
			(layer "B.Fab")
			(effects
				(font
					(size 0.7 0.7)
					(thickness 0.15)
				)
				(justify left bottom mirror)
			)
		)
		(pad "1" smd roundrect
			(at -0.48 0 270)
			(size 0.59 0.64)
			(layers "B.Cu" "B.Mask" "B.Paste")
			(roundrect_rratio 0.25)
			(net 417 "GND")
			(pintype "passive")
		)
		(pad "2" smd roundrect
			(at 0.48 0 270)
			(size 0.59 0.64)
			(layers "B.Cu" "B.Mask" "B.Paste")
			(roundrect_rratio 0.25)
			(net 50 "+3V3")
			(pintype "passive")
		)
	)
	(footprint "antmicro-footprints:C_0402_1005Metric"
		(layer "B.Cu")
		(at 197.04 136.674 90)
		(descr "Capacitor SMD 0402")
		(tags "capacitor SMD 0402")
		(property "Reference" "C59"
			(at 7.224 -9.615 270)
			(layer "B.SilkS")
			(effects
				(font
					(size 0.7 0.7)
					(thickness 0.15)
				)
				(justify left bottom mirror)
			)
		)
		(property "Value" "C_100n_0402"
			(at -1.022927 -2.155213 270)
			(layer "B.Fab")
			(hide yes)
			(effects
				(font
					(size 0.7 0.7)
					(thickness 0.15)
				)
				(justify left bottom mirror)
			)
		)
		(property "Datasheet" "https://www.murata.com/products/productdetail?partno=GRM155R61H104KE14%23"
			(at 0 0 90)
			(layer "F.Fab")
			(hide yes)
			(effects
				(font
					(size 1.27 1.27)
					(thickness 0.15)
				)
			)
		)
		(property "Description" "SMD Multilayer Ceramic Capacitor, 0.1 µF, 50 V, 0402 [1005 Metric], ± 10%, X5R, GRM Series"
			(at 0 0 90)
			(layer "F.Fab")
			(hide yes)
			(effects
				(font
					(size 1.27 1.27)
					(thickness 0.15)
				)
			)
		)
		(property "Author" "Antmicro"
			(at 333.714 -60.366 0)
			(layer "B.Fab")
			(hide yes)
			(effects
				(font
					(size 1 1)
					(thickness 0.15)
				)
				(justify mirror)
			)
		)
		(property "Dielectric" "X5R"
			(at 333.714 -60.366 0)
			(layer "B.Fab")
			(hide yes)
			(effects
				(font
					(size 1 1)
					(thickness 0.15)
				)
				(justify mirror)
			)
		)
		(property "License" "Apache-2.0"
			(at 333.714 -60.366 0)
			(layer "B.Fab")
			(hide yes)
			(effects
				(font
					(size 1 1)
					(thickness 0.15)
				)
				(justify mirror)
			)
		)
		(property "MPN" "GRM155R61H104KE14D"
			(at 333.714 -60.366 0)
			(layer "B.Fab")
			(hide yes)
			(effects
				(font
					(size 1 1)
					(thickness 0.15)
				)
				(justify mirror)
			)
		)
		(property "Manufacturer" "Murata"
			(at 333.714 -60.366 0)
			(layer "B.Fab")
			(hide yes)
			(effects
				(font
					(size 1 1)
					(thickness 0.15)
				)
				(justify mirror)
			)
		)
		(property "Public" ""
			(at 333.714 -60.366 0)
			(layer "B.Fab")
			(hide yes)
			(effects
				(font
					(size 1 1)
					(thickness 0.15)
				)
				(justify mirror)
			)
		)
		(property "Val" "100n"
			(at 333.714 -60.366 0)
			(layer "B.Fab")
			(hide yes)
			(effects
				(font
					(size 1 1)
					(thickness 0.15)
				)
				(justify mirror)
			)
		)
		(property "Voltage" "50V"
			(at 333.714 -60.366 0)
			(layer "B.Fab")
			(hide yes)
			(effects
				(font
					(size 1 1)
					(thickness 0.15)
				)
				(justify mirror)
			)
		)
		(sheetname "/FPGA Supply/")
		(sheetfile "fpga-supply.kicad_sch")
		(attr smd)
		(fp_rect
			(start -0.925 0.47)
			(end 0.925 -0.47)
			(stroke
				(width 0.05)
				(type default)
			)
			(fill no)
			(layer "B.CrtYd")
		)
		(fp_line
			(start 0.504 -0.248)
			(end -0.494 -0.248)
			(stroke
				(width 0.15)
				(type solid)
			)
			(layer "B.Fab")
		)
		(fp_line
			(start -0.494 -0.248)
			(end -0.494 0.25)
			(stroke
				(width 0.15)
				(type solid)
			)
			(layer "B.Fab")
		)
		(fp_line
			(start 0.504 0.25)
			(end 0.504 -0.248)
			(stroke
				(width 0.15)
				(type solid)
			)
			(layer "B.Fab")
		)
		(fp_line
			(start -0.494 0.25)
			(end 0.504 0.25)
			(stroke
				(width 0.15)
				(type solid)
			)
			(layer "B.Fab")
		)
		(fp_text user "${REFERENCE}"
			(at -0.939 -4.599 270)
			(layer "B.Fab")
			(effects
				(font
					(size 0.7 0.7)
					(thickness 0.15)
				)
				(justify left bottom mirror)
			)
		)
		(fp_text user "License: Apache-2.0"
			(at -0.939 -5.799 270)
			(layer "B.Fab")
			(effects
				(font
					(size 0.7 0.7)
					(thickness 0.15)
				)
				(justify left bottom mirror)
			)
		)
		(fp_text user "Author: Antmicro"
			(at -0.939 -3.399 270)
			(layer "B.Fab")
			(effects
				(font
					(size 0.7 0.7)
					(thickness 0.15)
				)
				(justify left bottom mirror)
			)
		)
		(pad "1" smd roundrect
			(at -0.48 0 90)
			(size 0.59 0.64)
			(layers "B.Cu" "B.Mask" "B.Paste")
			(roundrect_rratio 0.25)
			(net 417 "GND")
			(pintype "passive")
		)
		(pad "2" smd roundrect
			(at 0.48 0 90)
			(size 0.59 0.64)
			(layers "B.Cu" "B.Mask" "B.Paste")
			(roundrect_rratio 0.25)
			(net 47 "+1V05")
			(pintype "passive")
		)
	)
	(footprint "antmicro-footprints:C_0402_1005Metric"
		(layer "B.Cu")
		(at 198.94 136.664 90)
		(descr "Capacitor SMD 0402")
		(tags "capacitor SMD 0402")
		(property "Reference" "C48"
			(at 4.564 -9.615 90)
			(layer "B.SilkS")
			(effects
				(font
					(size 0.7 0.7)
					(thickness 0.15)
				)
				(justify right bottom mirror)
			)
		)
		(property "Value" "C_47n_0402"
			(at -1.022927 -2.155213 90)
			(layer "B.Fab")
			(hide yes)
			(effects
				(font
					(size 0.7 0.7)
					(thickness 0.15)
				)
				(justify right bottom mirror)
			)
		)
		(property "Datasheet" "https://www.murata.com/en-us/products/productdetail?partno=GRM155R61C473KA01%23"
			(at 0 0 90)
			(layer "F.Fab")
			(hide yes)
			(effects
				(font
					(size 1.27 1.27)
					(thickness 0.15)
				)
			)
		)
		(property "Description" "SMD Multilayer Ceramic Capacitor, 47000 pF, 16 V, 0402 [1005 Metric], ± 10%, X5R, MC"
			(at 0 0 90)
			(layer "F.Fab")
			(hide yes)
			(effects
				(font
					(size 1.27 1.27)
					(thickness 0.15)
				)
			)
		)
		(property "Author" "Antmicro"
			(at 335.604 -62.276 0)
			(layer "B.Fab")
			(hide yes)
			(effects
				(font
					(size 1 1)
					(thickness 0.15)
				)
				(justify mirror)
			)
		)
		(property "Dielectric" "X5R"
			(at 335.604 -62.276 0)
			(layer "B.Fab")
			(hide yes)
			(effects
				(font
					(size 1 1)
					(thickness 0.15)
				)
				(justify mirror)
			)
		)
		(property "License" "Apache-2.0"
			(at 335.604 -62.276 0)
			(layer "B.Fab")
			(hide yes)
			(effects
				(font
					(size 1 1)
					(thickness 0.15)
				)
				(justify mirror)
			)
		)
		(property "MPN" "GRM155R61C473KA01D"
			(at 335.604 -62.276 0)
			(layer "B.Fab")
			(hide yes)
			(effects
				(font
					(size 1 1)
					(thickness 0.15)
				)
				(justify mirror)
			)
		)
		(property "Manufacturer" "Murata"
			(at 335.604 -62.276 0)
			(layer "B.Fab")
			(hide yes)
			(effects
				(font
					(size 1 1)
					(thickness 0.15)
				)
				(justify mirror)
			)
		)
		(property "Public" ""
			(at 335.604 -62.276 0)
			(layer "B.Fab")
			(hide yes)
			(effects
				(font
					(size 1 1)
					(thickness 0.15)
				)
				(justify mirror)
			)
		)
		(property "Val" "47n"
			(at 335.604 -62.276 0)
			(layer "B.Fab")
			(hide yes)
			(effects
				(font
					(size 1 1)
					(thickness 0.15)
				)
				(justify mirror)
			)
		)
		(property "Voltage" "10V"
			(at 335.604 -62.276 0)
			(layer "B.Fab")
			(hide yes)
			(effects
				(font
					(size 1 1)
					(thickness 0.15)
				)
				(justify mirror)
			)
		)
		(sheetname "/FPGA Supply/")
		(sheetfile "fpga-supply.kicad_sch")
		(attr smd)
		(fp_rect
			(start -0.925 0.47)
			(end 0.925 -0.47)
			(stroke
				(width 0.05)
				(type default)
			)
			(fill no)
			(layer "B.CrtYd")
		)
		(fp_line
			(start 0.504 -0.248)
			(end -0.494 -0.248)
			(stroke
				(width 0.15)
				(type solid)
			)
			(layer "B.Fab")
		)
		(fp_line
			(start -0.494 -0.248)
			(end -0.494 0.25)
			(stroke
				(width 0.15)
				(type solid)
			)
			(layer "B.Fab")
		)
		(fp_line
			(start 0.504 0.25)
			(end 0.504 -0.248)
			(stroke
				(width 0.15)
				(type solid)
			)
			(layer "B.Fab")
		)
		(fp_line
			(start -0.494 0.25)
			(end 0.504 0.25)
			(stroke
				(width 0.15)
				(type solid)
			)
			(layer "B.Fab")
		)
		(fp_text user "Author: Antmicro"
			(at -0.939 -3.399 270)
			(layer "B.Fab")
			(effects
				(font
					(size 0.7 0.7)
					(thickness 0.15)
				)
				(justify left bottom mirror)
			)
		)
		(fp_text user "License: Apache-2.0"
			(at -0.939 -5.799 270)
			(layer "B.Fab")
			(effects
				(font
					(size 0.7 0.7)
					(thickness 0.15)
				)
				(justify left bottom mirror)
			)
		)
		(fp_text user "${REFERENCE}"
			(at -0.939 -4.599 270)
			(layer "B.Fab")
			(effects
				(font
					(size 0.7 0.7)
					(thickness 0.15)
				)
				(justify left bottom mirror)
			)
		)
		(pad "1" smd roundrect
			(at -0.48 0 90)
			(size 0.59 0.64)
			(layers "B.Cu" "B.Mask" "B.Paste")
			(roundrect_rratio 0.25)
			(net 417 "GND")
			(pintype "passive")
		)
		(pad "2" smd roundrect
			(at 0.48 0 90)
			(size 0.59 0.64)
			(layers "B.Cu" "B.Mask" "B.Paste")
			(roundrect_rratio 0.25)
			(net 47 "+1V05")
			(pintype "passive")
		)
	)
)
